(kicad_pcb
	(version 20260206)
	(generator "pcbnew")
	(generator_version "10.0")
	(general
		(thickness 1.6)
		(legacy_teardrops no)
	)
	(paper "A4")
	(title_block
		(title "Wiwynn_Tioga_Pass_MB.brd")
		(comment 1 "Tioga Pass / footprints 270-278 of 4770")
	)
	(layers
		(0 "F.Cu" signal "TOP")
		(4 "In1.Cu" signal "L2GND")
		(6 "In2.Cu" signal "L3")
		(8 "In3.Cu" signal "L4GND")
		(10 "In4.Cu" signal "L5")
		(12 "In5.Cu" signal "L6GND")
		(14 "In6.Cu" signal "L7VCC")
		(16 "In7.Cu" signal "L8VCC")
		(18 "In8.Cu" signal "L9GND")
		(20 "In9.Cu" signal "L10")
		(22 "In10.Cu" signal "L11GND")
		(24 "In11.Cu" signal "L12")
		(26 "In12.Cu" signal "L13GND")
		(2 "B.Cu" signal "BOTTOM")
		(9 "F.Adhes" user "F.Adhesive")
		(11 "B.Adhes" user "B.Adhesive")
		(13 "F.Paste" user "Package Geometry/Pastemask Top")
		(15 "B.Paste" user "Package Geometry/Pastemask Bottom")
		(5 "F.SilkS" user "Ref Des/Silkscreen Top")
		(7 "B.SilkS" user "Ref Des/Silkscreen Bottom")
		(1 "F.Mask" user "Board Geometry/Soldermask Top")
		(3 "B.Mask" user "Board Geometry/Soldermask Bottom")
		(17 "Dwgs.User" user "User.Drawings")
		(19 "Cmts.User" user "User.Comments")
		(21 "Eco1.User" user "User.Eco1")
		(23 "Eco2.User" user "User.Eco2")
		(25 "Edge.Cuts" user "Board Geometry/Outline")
		(27 "Margin" user)
		(31 "F.CrtYd" user "Package Geometry/Place Bound Top")
		(29 "B.CrtYd" user "Package Geometry/Place Bound Bottom")
		(35 "F.Fab" user "Ref Des/Assembly Top")
		(33 "B.Fab" user "Ref Des/Assembly Bottom")
	)
	(footprint ""
		(layer "F.Cu")
		(at 471.000074 1.999996 90)
		(property "Reference" "TH9G1"
			(at 4.640326 1.820926 0)
			(unlocked yes)
			(layer "F.SilkS")
			(effects
				(font
					(size 0.7874 0.5842)
					(thickness 0.1524)
				)
				(justify left)
			)
		)
		(property "Value" ""
			(at 0 0 90)
			(layer "F.Fab")
			(effects
				(font
					(size 1.27 1.27)
				)
			)
		)
		(duplicate_pad_numbers_are_jumpers no)
		(fp_poly
			(pts
				(arc
					(start 3.0226 0.68834)
					(mid 3.042235 0.827855)
					(end 3.099562 0.956564)
				)
				(arc
					(start 3.099562 0.956564)
					(mid 4.012804 3.550073)
					(end 3.042158 6.12267)
				)
				(arc
					(start 3.042158 6.12267)
					(mid 0 7.518589)
					(end -3.042158 6.12267)
				)
				(arc
					(start -3.042158 6.12267)
					(mid -4.012854 3.55061)
					(end -3.100324 0.957326)
				)
				(arc
					(start -3.100324 0.957326)
					(mid -3.042498 0.827518)
					(end -3.0226 0.686816)
				)
				(arc
					(start -3.0226 -0.000254)
					(mid -2.137121 -2.137227)
					(end 0 -3.022346)
				)
				(arc
					(start 0 -3.022346)
					(mid 2.137227 -2.136973)
					(end 3.0226 0.000254)
				)
			)
			(stroke
				(width 0)
				(type default)
			)
			(fill no)
			(layer "F.CrtYd")
		)
		(pad "1" thru_hole custom
			(at 0 0 90)
			(size 2.00667 2.00667)
			(drill 0.3048)
			(layers "*.Cu" "*.Mask")
			(remove_unused_layers no)
			(net "GND")
			(clearance -0.889)
			(options
				(clearance outline)
				(anchor circle)
			)
			(primitives
				(gr_poly
					(pts
						(arc
							(start 3.042158 3.874516)
							(mid 0 5.270435)
							(end -3.042158 3.874516)
						)
						(arc
							(start -3.042158 3.874516)
							(mid -4.012854 1.302456)
							(end -3.100324 -1.290828)
						)
						(arc
							(start -3.100324 -1.290828)
							(mid -3.042498 -1.420636)
							(end -3.0226 -1.561338)
						)
						(arc
							(start -3.0226 -2.248408)
							(mid -2.137121 -4.385381)
							(end 0 -5.2705)
						)
						(arc
							(start 0 -5.2705)
							(mid 2.137227 -4.385127)
							(end 3.0226 -2.2479)
						)
						(arc
							(start 3.0226 -1.55956)
							(mid 3.04227 -1.420177)
							(end 3.099562 -1.29159)
						)
						(arc
							(start 3.099562 -1.29159)
							(mid 4.012804 1.301919)
							(end 3.042158 3.874516)
						)
					)
					(width 0)
					(fill yes)
				)
			)
		)
	)
	(footprint ""
		(layer "F.Cu")
		(at 273.2532 -79.6036 180)
		(property "Reference" "C5D21"
			(at 0 0 180)
			(layer "F.SilkS")
			(hide yes)
			(effects
				(font
					(size 1.27 1.27)
				)
			)
		)
		(property "Value" ""
			(at 0 0 180)
			(layer "F.Fab")
			(effects
				(font
					(size 1.27 1.27)
				)
			)
		)
		(duplicate_pad_numbers_are_jumpers no)
		(fp_poly
			(pts
				(xy -0.4953 -0.2032) (xy 0.4953 -0.2032) (xy 0.4953 1.6002) (xy -0.4953 1.6002)
			)
			(stroke
				(width 0)
				(type default)
			)
			(fill no)
			(layer "F.CrtYd")
		)
		(fp_line
			(start 0.4953 1.6002)
			(end -0.4953 1.6002)
			(stroke
				(width 0.1)
				(type default)
			)
			(layer "F.Fab")
		)
		(fp_line
			(start 0.4953 -0.2032)
			(end 0.4953 1.6002)
			(stroke
				(width 0.1)
				(type default)
			)
			(layer "F.Fab")
		)
		(fp_line
			(start -0.4953 1.6002)
			(end -0.4953 -0.2032)
			(stroke
				(width 0.1)
				(type default)
			)
			(layer "F.Fab")
		)
		(fp_line
			(start -0.4953 -0.2032)
			(end 0.4953 -0.2032)
			(stroke
				(width 0.1)
				(type default)
			)
			(layer "F.Fab")
		)
		(pad "1" smd rect
			(at 0 0 180)
			(size 0.762 0.889)
			(layers "F.Cu" "F.Mask" "F.Paste")
			(net "PVCCMCP_CPU0")
		)
		(pad "2" smd rect
			(at 0 1.397 180)
			(size 0.762 0.889)
			(layers "F.Cu" "F.Mask" "F.Paste")
			(net "GND")
		)
		(zone
			(layer "F.Cu")
			(hatch none 0.5)
			(connect_pads
				(clearance 0)
			)
			(min_thickness 0.25)
			(keepout
				(tracks not_allowed)
				(vias allowed)
				(pads allowed)
				(copperpour not_allowed)
				(footprints allowed)
			)
			(placement
				(enabled no)
				(sheetname "")
			)
			(fill
				(thermal_gap 0.5)
				(thermal_bridge_width 0.5)
				(island_removal_mode 0)
			)
			(polygon
				(pts
					(xy 273.6342 -80.0481) (xy 272.8722 -80.0481) (xy 272.8722 -80.5561) (xy 273.6342 -80.5561)
				)
			)
		)
	)
	(footprint ""
		(layer "F.Cu")
		(at 405.231092 -10.917936)
		(property "Reference" "C8G5"
			(at 0 0 0)
			(layer "F.SilkS")
			(hide yes)
			(effects
				(font
					(size 1.27 1.27)
				)
			)
		)
		(property "Value" ""
			(at 0 0 0)
			(layer "F.Fab")
			(effects
				(font
					(size 1.27 1.27)
				)
			)
		)
		(duplicate_pad_numbers_are_jumpers no)
		(fp_rect
			(start -0.3048 0.9906)
			(end 0.3048 -0.1016)
			(stroke
				(width 0)
				(type default)
			)
			(fill no)
			(layer "F.CrtYd")
		)
		(fp_line
			(start -0.3048 -0.1016)
			(end -0.3048 0.9906)
			(stroke
				(width 0.1)
				(type default)
			)
			(layer "F.Fab")
		)
		(fp_line
			(start -0.3048 0.9906)
			(end 0.3048 0.9906)
			(stroke
				(width 0.1)
				(type default)
			)
			(layer "F.Fab")
		)
		(fp_line
			(start 0.3048 -0.1016)
			(end -0.3048 -0.1016)
			(stroke
				(width 0.1)
				(type default)
			)
			(layer "F.Fab")
		)
		(fp_line
			(start 0.3048 0.9906)
			(end 0.3048 -0.1016)
			(stroke
				(width 0.1)
				(type default)
			)
			(layer "F.Fab")
		)
		(pad "1" smd rect
			(at 0 0)
			(size 0.508 0.508)
			(layers "F.Cu" "F.Mask" "F.Paste")
			(net "P3E_CPU0_PE2_SS_TXP<2>")
		)
		(pad "2" smd rect
			(at 0 0.889)
			(size 0.508 0.508)
			(layers "F.Cu" "F.Mask" "F.Paste")
			(net "P3E_CPU0_PE2_SS_C_TXP<2>")
		)
		(zone
			(layer "F.Cu")
			(hatch none 0.5)
			(connect_pads
				(clearance 0)
			)
			(min_thickness 0.25)
			(keepout
				(tracks allowed)
				(vias not_allowed)
				(pads allowed)
				(copperpour not_allowed)
				(footprints allowed)
			)
			(placement
				(enabled no)
				(sheetname "")
			)
			(fill
				(thermal_gap 0.5)
				(thermal_bridge_width 0.5)
				(island_removal_mode 0)
			)
			(polygon
				(pts
					(xy 404.977092 -10.282936) (xy 405.485092 -10.282936) (xy 405.485092 -10.663936) (xy 404.977092 -10.663936)
				)
			)
		)
		(zone
			(layer "F.Cu")
			(hatch none 0.5)
			(connect_pads
				(clearance 0)
			)
			(min_thickness 0.25)
			(keepout
				(tracks not_allowed)
				(vias allowed)
				(pads allowed)
				(copperpour not_allowed)
				(footprints allowed)
			)
			(placement
				(enabled no)
				(sheetname "")
			)
			(fill
				(thermal_gap 0.5)
				(thermal_bridge_width 0.5)
				(island_removal_mode 0)
			)
			(polygon
				(pts
					(xy 404.977092 -10.282936) (xy 405.485092 -10.282936) (xy 405.485092 -10.663936) (xy 404.977092 -10.663936)
				)
			)
		)
	)
	(footprint ""
		(layer "F.Cu")
		(at 214.503 -63.11392)
		(property "Reference" "C4E3"
			(at 0 0 0)
			(layer "F.SilkS")
			(hide yes)
			(effects
				(font
					(size 1.27 1.27)
				)
			)
		)
		(property "Value" ""
			(at 0 0 0)
			(layer "F.Fab")
			(effects
				(font
					(size 1.27 1.27)
				)
			)
		)
		(duplicate_pad_numbers_are_jumpers no)
		(fp_poly
			(pts
				(xy -0.4953 -0.2032) (xy 0.4953 -0.2032) (xy 0.4953 1.6002) (xy -0.4953 1.6002)
			)
			(stroke
				(width 0)
				(type default)
			)
			(fill no)
			(layer "F.CrtYd")
		)
		(fp_line
			(start -0.4953 -0.2032)
			(end 0.4953 -0.2032)
			(stroke
				(width 0.1)
				(type default)
			)
			(layer "F.Fab")
		)
		(fp_line
			(start -0.4953 1.6002)
			(end -0.4953 -0.2032)
			(stroke
				(width 0.1)
				(type default)
			)
			(layer "F.Fab")
		)
		(fp_line
			(start 0.4953 -0.2032)
			(end 0.4953 1.6002)
			(stroke
				(width 0.1)
				(type default)
			)
			(layer "F.Fab")
		)
		(fp_line
			(start 0.4953 1.6002)
			(end -0.4953 1.6002)
			(stroke
				(width 0.1)
				(type default)
			)
			(layer "F.Fab")
		)
		(pad "1" smd rect
			(at 0 0)
			(size 0.762 0.889)
			(layers "F.Cu" "F.Mask" "F.Paste")
			(net "PVCCIN_CPU0")
		)
		(pad "2" smd rect
			(at 0 1.397)
			(size 0.762 0.889)
			(layers "F.Cu" "F.Mask" "F.Paste")
			(net "GND")
		)
		(zone
			(layer "F.Cu")
			(hatch none 0.5)
			(connect_pads
				(clearance 0)
			)
			(min_thickness 0.25)
			(keepout
				(tracks not_allowed)
				(vias allowed)
				(pads allowed)
				(copperpour not_allowed)
				(footprints allowed)
			)
			(placement
				(enabled no)
				(sheetname "")
			)
			(fill
				(thermal_gap 0.5)
				(thermal_bridge_width 0.5)
				(island_removal_mode 0)
			)
			(polygon
				(pts
					(xy 214.122 -62.66942) (xy 214.884 -62.66942) (xy 214.884 -62.16142) (xy 214.122 -62.16142)
				)
			)
		)
	)
	(footprint ""
		(layer "F.Cu")
		(at -1.59639 -150.10511 -90)
		(property "Reference" "C1A9"
			(at 0 0 270)
			(layer "F.SilkS")
			(hide yes)
			(effects
				(font
					(size 1.27 1.27)
				)
			)
		)
		(property "Value" ""
			(at 0 0 270)
			(layer "F.Fab")
			(effects
				(font
					(size 1.27 1.27)
				)
			)
		)
		(duplicate_pad_numbers_are_jumpers no)
		(fp_poly
			(pts
				(xy 0.3048 -0.1016) (xy 0.3048 0.9906) (xy -0.3048 0.9906) (xy -0.3048 -0.1016)
			)
			(stroke
				(width 0)
				(type default)
			)
			(fill no)
			(layer "F.CrtYd")
		)
		(fp_line
			(start -0.3048 0.9906)
			(end 0.3048 0.9906)
			(stroke
				(width 0.1)
				(type default)
			)
			(layer "F.Fab")
		)
		(fp_line
			(start 0.3048 0.9906)
			(end 0.3048 -0.1016)
			(stroke
				(width 0.1)
				(type default)
			)
			(layer "F.Fab")
		)
		(fp_line
			(start -0.3048 -0.1016)
			(end -0.3048 0.9906)
			(stroke
				(width 0.1)
				(type default)
			)
			(layer "F.Fab")
		)
		(fp_line
			(start 0.3048 -0.1016)
			(end -0.3048 -0.1016)
			(stroke
				(width 0.1)
				(type default)
			)
			(layer "F.Fab")
		)
		(pad "1" smd rect
			(at 0 0 270)
			(size 0.508 0.508)
			(layers "F.Cu" "F.Mask" "F.Paste")
			(net "VR_FET_SW_P12V_STBY_PVDDQ_KLM")
		)
		(pad "2" smd rect
			(at 0 0.889 270)
			(size 0.508 0.508)
			(layers "F.Cu" "F.Mask" "F.Paste")
			(net "GND")
		)
		(zone
			(layer "F.Cu")
			(hatch none 0.5)
			(connect_pads
				(clearance 0)
			)
			(min_thickness 0.25)
			(keepout
				(tracks not_allowed)
				(vias allowed)
				(pads allowed)
				(copperpour not_allowed)
				(footprints allowed)
			)
			(placement
				(enabled no)
				(sheetname "")
			)
			(fill
				(thermal_gap 0.5)
				(thermal_bridge_width 0.5)
				(island_removal_mode 0)
			)
			(polygon
				(pts
					(xy -2.23139 -150.35911) (xy -2.23139 -149.85111) (xy -1.85039 -149.85111) (xy -1.85039 -150.35911)
				)
			)
		)
		(zone
			(layer "F.Cu")
			(hatch none 0.5)
			(connect_pads
				(clearance 0)
			)
			(min_thickness 0.25)
			(keepout
				(tracks allowed)
				(vias not_allowed)
				(pads allowed)
				(copperpour not_allowed)
				(footprints allowed)
			)
			(placement
				(enabled no)
				(sheetname "")
			)
			(fill
				(thermal_gap 0.5)
				(thermal_bridge_width 0.5)
				(island_removal_mode 0)
			)
			(polygon
				(pts
					(xy -1.85039 -150.35911) (xy -1.85039 -149.85111) (xy -2.23139 -149.85111) (xy -2.23139 -150.35911)
				)
			)
		)
	)
	(footprint ""
		(layer "F.Cu")
		(at 104.645206 -68.365116 180)
		(property "Reference" "C2D46"
			(at 0 0 180)
			(layer "F.SilkS")
			(hide yes)
			(effects
				(font
					(size 1.27 1.27)
				)
			)
		)
		(property "Value" ""
			(at 0 0 180)
			(layer "F.Fab")
			(effects
				(font
					(size 1.27 1.27)
				)
			)
		)
		(duplicate_pad_numbers_are_jumpers no)
		(fp_poly
			(pts
				(xy -0.4953 -0.2032) (xy 0.4953 -0.2032) (xy 0.4953 1.6002) (xy -0.4953 1.6002)
			)
			(stroke
				(width 0)
				(type default)
			)
			(fill no)
			(layer "F.CrtYd")
		)
		(fp_line
			(start 0.4953 1.6002)
			(end -0.4953 1.6002)
			(stroke
				(width 0.1)
				(type default)
			)
			(layer "F.Fab")
		)
		(fp_line
			(start 0.4953 -0.2032)
			(end 0.4953 1.6002)
			(stroke
				(width 0.1)
				(type default)
			)
			(layer "F.Fab")
		)
		(fp_line
			(start -0.4953 1.6002)
			(end -0.4953 -0.2032)
			(stroke
				(width 0.1)
				(type default)
			)
			(layer "F.Fab")
		)
		(fp_line
			(start -0.4953 -0.2032)
			(end 0.4953 -0.2032)
			(stroke
				(width 0.1)
				(type default)
			)
			(layer "F.Fab")
		)
		(pad "1" smd rect
			(at 0 0 180)
			(size 0.762 0.889)
			(layers "F.Cu" "F.Mask" "F.Paste")
			(net "PVDDQ_GHJ")
		)
		(pad "2" smd rect
			(at 0 1.397 180)
			(size 0.762 0.889)
			(layers "F.Cu" "F.Mask" "F.Paste")
			(net "GND")
		)
		(zone
			(layer "F.Cu")
			(hatch none 0.5)
			(connect_pads
				(clearance 0)
			)
			(min_thickness 0.25)
			(keepout
				(tracks not_allowed)
				(vias allowed)
				(pads allowed)
				(copperpour not_allowed)
				(footprints allowed)
			)
			(placement
				(enabled no)
				(sheetname "")
			)
			(fill
				(thermal_gap 0.5)
				(thermal_bridge_width 0.5)
				(island_removal_mode 0)
			)
			(polygon
				(pts
					(xy 105.026206 -68.809616) (xy 104.264206 -68.809616) (xy 104.264206 -69.317616) (xy 105.026206 -69.317616)
				)
			)
		)
	)
	(footprint ""
		(layer "F.Cu")
		(at 446.73012 -24.47798)
		(property "Reference" "C25W15"
			(at -0.8382 -0.67818 0)
			(unlocked yes)
			(layer "F.SilkS")
			(effects
				(font
					(size 0.4064 0.254)
					(thickness 0.1524)
				)
				(justify left)
			)
		)
		(property "Value" ""
			(at 0 0 0)
			(layer "F.Fab")
			(effects
				(font
					(size 1.27 1.27)
				)
			)
		)
		(duplicate_pad_numbers_are_jumpers no)
		(fp_poly
			(pts
				(xy 0.3048 -0.1016) (xy 0.3048 0.9906) (xy -0.3048 0.9906) (xy -0.3048 -0.1016)
			)
			(stroke
				(width 0)
				(type default)
			)
			(fill no)
			(layer "F.CrtYd")
		)
		(fp_line
			(start -0.3048 -0.1016)
			(end -0.3048 0.9906)
			(stroke
				(width 0.1)
				(type default)
			)
			(layer "F.Fab")
		)
		(fp_line
			(start -0.3048 0.9906)
			(end 0.3048 0.9906)
			(stroke
				(width 0.1)
				(type default)
			)
			(layer "F.Fab")
		)
		(fp_line
			(start 0.3048 -0.1016)
			(end -0.3048 -0.1016)
			(stroke
				(width 0.1)
				(type default)
			)
			(layer "F.Fab")
		)
		(fp_line
			(start 0.3048 0.9906)
			(end 0.3048 -0.1016)
			(stroke
				(width 0.1)
				(type default)
			)
			(layer "F.Fab")
		)
		(pad "1" smd rect
			(at 0 0)
			(size 0.508 0.508)
			(layers "F.Cu" "F.Mask" "F.Paste")
			(net "P2V5_AUX_BMC")
		)
		(pad "2" smd rect
			(at 0 0.889)
			(size 0.508 0.508)
			(layers "F.Cu" "F.Mask" "F.Paste")
			(net "GND")
		)
		(zone
			(layer "F.Cu")
			(hatch none 0.5)
			(connect_pads
				(clearance 0)
			)
			(min_thickness 0.25)
			(keepout
				(tracks allowed)
				(vias not_allowed)
				(pads allowed)
				(copperpour not_allowed)
				(footprints allowed)
			)
			(placement
				(enabled no)
				(sheetname "")
			)
			(fill
				(thermal_gap 0.5)
				(thermal_bridge_width 0.5)
				(island_removal_mode 0)
			)
			(polygon
				(pts
					(xy 446.47612 -24.22398) (xy 446.98412 -24.22398) (xy 446.98412 -23.84298) (xy 446.47612 -23.84298)
				)
			)
		)
		(zone
			(layer "F.Cu")
			(hatch none 0.5)
			(connect_pads
				(clearance 0)
			)
			(min_thickness 0.25)
			(keepout
				(tracks not_allowed)
				(vias allowed)
				(pads allowed)
				(copperpour not_allowed)
				(footprints allowed)
			)
			(placement
				(enabled no)
				(sheetname "")
			)
			(fill
				(thermal_gap 0.5)
				(thermal_bridge_width 0.5)
				(island_removal_mode 0)
			)
			(polygon
				(pts
					(xy 446.47612 -23.84298) (xy 446.98412 -23.84298) (xy 446.98412 -24.22398) (xy 446.47612 -24.22398)
				)
			)
		)
	)
	(footprint ""
		(layer "F.Cu")
		(at 330.962 -153.543)
		(property "Reference" "C6A1"
			(at 0 0 0)
			(layer "F.SilkS")
			(hide yes)
			(effects
				(font
					(size 1.27 1.27)
				)
			)
		)
		(property "Value" ""
			(at 0 0 0)
			(layer "F.Fab")
			(effects
				(font
					(size 1.27 1.27)
				)
			)
		)
		(duplicate_pad_numbers_are_jumpers no)
		(fp_rect
			(start -0.7239 1.9939)
			(end 0.7239 -0.2159)
			(stroke
				(width 0)
				(type default)
			)
			(fill no)
			(layer "F.CrtYd")
		)
		(fp_line
			(start -0.7239 -0.2159)
			(end -0.7239 1.9939)
			(stroke
				(width 0.1)
				(type default)
			)
			(layer "F.Fab")
		)
		(fp_line
			(start -0.7239 1.9939)
			(end 0.7239 1.9939)
			(stroke
				(width 0.1)
				(type default)
			)
			(layer "F.Fab")
		)
		(fp_line
			(start 0.7239 -0.2159)
			(end -0.7239 -0.2159)
			(stroke
				(width 0.1)
				(type default)
			)
			(layer "F.Fab")
		)
		(fp_line
			(start 0.7239 1.9939)
			(end 0.7239 -0.2159)
			(stroke
				(width 0.1)
				(type default)
			)
			(layer "F.Fab")
		)
		(pad "1" smd rect
			(at 0 0)
			(size 1.27 1.016)
			(layers "F.Cu" "F.Mask" "F.Paste")
			(net "PVDDQ_DEF")
		)
		(pad "2" smd rect
			(at 0 1.778)
			(size 1.27 1.016)
			(layers "F.Cu" "F.Mask" "F.Paste")
			(net "GND")
		)
		(zone
			(layer "F.Cu")
			(hatch none 0.5)
			(connect_pads
				(clearance 0)
			)
			(min_thickness 0.25)
			(keepout
				(tracks not_allowed)
				(vias allowed)
				(pads allowed)
				(copperpour not_allowed)
				(footprints allowed)
			)
			(placement
				(enabled no)
				(sheetname "")
			)
			(fill
				(thermal_gap 0.5)
				(thermal_bridge_width 0.5)
				(island_removal_mode 0)
			)
			(polygon
				(pts
					(xy 330.327 -152.273) (xy 331.597 -152.273) (xy 331.597 -153.035) (xy 330.327 -153.035)
				)
			)
		)
	)
	(footprint ""
		(layer "F.Cu")
		(at 352.24593 -25.676606 90)
		(property "Reference" "C7F7"
			(at 0 0 90)
			(layer "F.SilkS")
			(hide yes)
			(effects
				(font
					(size 1.27 1.27)
				)
			)
		)
		(property "Value" "*"
			(at -0.0762 -6.2357 90)
			(unlocked yes)
			(layer "F.Fab")
			(hide yes)
			(effects
				(font
					(size 1.27 1.016)
					(thickness 0.1524)
				)
			)
		)
		(property "Device Type" "SC22U16V5MX-4-GP_SMD-BCG5-SC22A"
			(at -0.0762 -8.2677 90)
			(unlocked yes)
			(layer "F.Fab")
			(hide yes)
			(effects
				(font
					(size 1.27 1.016)
					(thickness 0.1524)
				)
			)
		)
		(duplicate_pad_numbers_are_jumpers no)
		(fp_line
			(start 0.635 0)
			(end -0.635 0)
			(stroke
				(width 0.508)
				(type default)
			)
			(layer "F.SilkS")
		)
		(fp_rect
			(start -0.9652 1.778)
			(end 0.9652 -1.778)
			(stroke
				(width 0)
				(type default)
			)
			(fill no)
			(layer "F.CrtYd")
		)
		(fp_poly
			(pts
				(xy -0.9652 -1.778) (xy 0.9652 -1.778) (xy 0.9652 1.778) (xy -0.9652 1.778)
			)
			(stroke
				(width 0)
				(type default)
			)
			(fill no)
			(layer "F.Fab")
		)
		(pad "1" smd rect
			(at 0 -0.9652 90)
			(size 1.397 1.143)
			(layers "F.Cu" "F.Mask" "F.Paste")
			(net "VR_FET_SW_P12V_STBY_PVPP_ABC")
		)
		(pad "2" smd rect
			(at 0 0.9652 90)
			(size 1.397 1.143)
			(layers "F.Cu" "F.Mask" "F.Paste")
			(net "GND")
		)
	)
)
